(kicad_pcb
	(version 20260206)
	(generator "pcbnew")
	(generator_version "10.0")
	(general
		(thickness 1.6)
		(legacy_teardrops no)
	)
	(paper "A4")
	(title_block
		(title "03242023_DA0F0TMBIJ0_F0T_Motherboard_J_brd_V01_OCP.brd")
		(comment 1 "Grand Teton / footprints 3183-3188 of 6105")
	)
	(layers
		(0 "F.Cu" signal "TOP")
		(4 "In1.Cu" signal "GND")
		(6 "In2.Cu" signal "IN1")
		(8 "In3.Cu" signal "GND1")
		(10 "In4.Cu" signal "IN2")
		(12 "In5.Cu" signal "GND2")
		(14 "In6.Cu" signal "IN3")
		(16 "In7.Cu" signal "GND3")
		(18 "In8.Cu" signal "VCC")
		(20 "In9.Cu" signal "VCC1")
		(22 "In10.Cu" signal "GND4")
		(24 "In11.Cu" signal "IN4")
		(26 "In12.Cu" signal "GND5")
		(28 "In13.Cu" signal "IN5")
		(30 "In14.Cu" signal "GND6")
		(32 "In15.Cu" signal "IN6")
		(34 "In16.Cu" signal "GND7")
		(2 "B.Cu" signal "BOTTOM")
		(9 "F.Adhes" user "F.Adhesive")
		(11 "B.Adhes" user "B.Adhesive")
		(13 "F.Paste" user "Package Geometry/Pastemask Top")
		(15 "B.Paste" user "Package Geometry/Pastemask Bottom")
		(5 "F.SilkS" user "Ref Des/Silkscreen Top")
		(7 "B.SilkS" user "Ref Des/Silkscreen Bottom")
		(1 "F.Mask" user "Board Geometry/Soldermask Top")
		(3 "B.Mask" user "Board Geometry/Soldermask Bottom")
		(17 "Dwgs.User" user "User.Drawings")
		(19 "Cmts.User" user "User.Comments")
		(21 "Eco1.User" user "User.Eco1")
		(23 "Eco2.User" user "User.Eco2")
		(25 "Edge.Cuts" user "Board Geometry/Outline")
		(27 "Margin" user)
		(31 "F.CrtYd" user "Package Geometry/Place Bound Top")
		(29 "B.CrtYd" user "Package Geometry/Place Bound Bottom")
		(35 "F.Fab" user "Ref Des/Assembly Top")
		(33 "B.Fab" user "Ref Des/Assembly Bottom")
	)
	(footprint ""
		(layer "F.Cu")
		(at 168.449498 -356.03053 90)
		(property "Reference" "PC395"
			(at 0 0 90)
			(layer "F.SilkS")
			(hide yes)
			(effects
				(font
					(size 1.27 1.27)
				)
			)
		)
		(property "Value" ""
			(at 0 0 90)
			(layer "F.Fab")
			(effects
				(font
					(size 1.27 1.27)
				)
			)
		)
		(duplicate_pad_numbers_are_jumpers no)
		(fp_line
			(start 0.7874 -0.4064)
			(end 0.7874 0.4064)
			(stroke
				(width 0.1524)
				(type default)
			)
			(layer "F.SilkS")
		)
		(fp_line
			(start -0.7874 -0.4064)
			(end 0.7874 -0.4064)
			(stroke
				(width 0.1524)
				(type default)
			)
			(layer "F.SilkS")
		)
		(fp_line
			(start 0.7874 0.4064)
			(end -0.7874 0.4064)
			(stroke
				(width 0.1524)
				(type default)
			)
			(layer "F.SilkS")
		)
		(fp_line
			(start -0.7874 0.4064)
			(end -0.7874 -0.4064)
			(stroke
				(width 0.1524)
				(type default)
			)
			(layer "F.SilkS")
		)
		(fp_line
			(start -0.12065 -0.305054)
			(end -0.12065 -0.2794)
			(stroke
				(width 0.1)
				(type default)
			)
			(layer "F.Fab")
		)
		(fp_line
			(start -0.67945 -0.305054)
			(end -0.12065 -0.305054)
			(stroke
				(width 0.1)
				(type default)
			)
			(layer "F.Fab")
		)
		(fp_line
			(start 0.67945 -0.3048)
			(end 0.67945 0.3048)
			(stroke
				(width 0.1)
				(type default)
			)
			(layer "F.Fab")
		)
		(fp_line
			(start 0.12065 -0.3048)
			(end 0.67945 -0.3048)
			(stroke
				(width 0.1)
				(type default)
			)
			(layer "F.Fab")
		)
		(fp_line
			(start 0.12065 -0.2794)
			(end 0.12065 -0.3048)
			(stroke
				(width 0.1)
				(type default)
			)
			(layer "F.Fab")
		)
		(fp_line
			(start -0.12065 -0.2794)
			(end 0.12065 -0.2794)
			(stroke
				(width 0.1)
				(type default)
			)
			(layer "F.Fab")
		)
		(fp_line
			(start 0.120396 0.2794)
			(end -0.12065 0.2794)
			(stroke
				(width 0.1)
				(type default)
			)
			(layer "F.Fab")
		)
		(fp_line
			(start -0.12065 0.2794)
			(end -0.12065 0.3048)
			(stroke
				(width 0.1)
				(type default)
			)
			(layer "F.Fab")
		)
		(fp_line
			(start 0.67945 0.3048)
			(end 0.120396 0.3048)
			(stroke
				(width 0.1)
				(type default)
			)
			(layer "F.Fab")
		)
		(fp_line
			(start 0.120396 0.3048)
			(end 0.120396 0.2794)
			(stroke
				(width 0.1)
				(type default)
			)
			(layer "F.Fab")
		)
		(fp_line
			(start -0.12065 0.3048)
			(end -0.67945 0.3048)
			(stroke
				(width 0.1)
				(type default)
			)
			(layer "F.Fab")
		)
		(fp_line
			(start -0.67945 0.3048)
			(end -0.67945 -0.305054)
			(stroke
				(width 0.1)
				(type default)
			)
			(layer "F.Fab")
		)
		(pad "1" smd circle
			(at -0.40005 0 90)
			(size 0 0)
			(layers "F.Cu" "F.Mask" "F.Paste")
			(net "PVCCFA_EHV_FIVRA_CPU1_VDD1")
		)
		(pad "2" smd circle
			(at 0.40005 0 90)
			(size 0 0)
			(layers "F.Cu" "F.Mask" "F.Paste")
			(net "GND")
		)
	)
	(footprint ""
		(layer "F.Cu")
		(at 362.646468 -362.618528)
		(property "Reference" "PC334"
			(at 0 0 0)
			(layer "F.SilkS")
			(hide yes)
			(effects
				(font
					(size 1.27 1.27)
				)
			)
		)
		(property "Value" ""
			(at 0 0 0)
			(layer "F.Fab")
			(effects
				(font
					(size 1.27 1.27)
				)
			)
		)
		(duplicate_pad_numbers_are_jumpers no)
		(fp_line
			(start -0.7874 -0.4064)
			(end 0.7874 -0.4064)
			(stroke
				(width 0.1524)
				(type default)
			)
			(layer "F.SilkS")
		)
		(fp_line
			(start -0.7874 0.4064)
			(end -0.7874 -0.4064)
			(stroke
				(width 0.1524)
				(type default)
			)
			(layer "F.SilkS")
		)
		(fp_line
			(start 0.7874 -0.4064)
			(end 0.7874 0.4064)
			(stroke
				(width 0.1524)
				(type default)
			)
			(layer "F.SilkS")
		)
		(fp_line
			(start 0.7874 0.4064)
			(end -0.7874 0.4064)
			(stroke
				(width 0.1524)
				(type default)
			)
			(layer "F.SilkS")
		)
		(fp_line
			(start -0.67945 -0.305054)
			(end -0.12065 -0.305054)
			(stroke
				(width 0.1)
				(type default)
			)
			(layer "F.Fab")
		)
		(fp_line
			(start -0.67945 0.3048)
			(end -0.67945 -0.305054)
			(stroke
				(width 0.1)
				(type default)
			)
			(layer "F.Fab")
		)
		(fp_line
			(start -0.12065 -0.305054)
			(end -0.12065 -0.2794)
			(stroke
				(width 0.1)
				(type default)
			)
			(layer "F.Fab")
		)
		(fp_line
			(start -0.12065 -0.2794)
			(end 0.12065 -0.2794)
			(stroke
				(width 0.1)
				(type default)
			)
			(layer "F.Fab")
		)
		(fp_line
			(start -0.12065 0.2794)
			(end -0.12065 0.3048)
			(stroke
				(width 0.1)
				(type default)
			)
			(layer "F.Fab")
		)
		(fp_line
			(start -0.12065 0.3048)
			(end -0.67945 0.3048)
			(stroke
				(width 0.1)
				(type default)
			)
			(layer "F.Fab")
		)
		(fp_line
			(start 0.120396 0.2794)
			(end -0.12065 0.2794)
			(stroke
				(width 0.1)
				(type default)
			)
			(layer "F.Fab")
		)
		(fp_line
			(start 0.120396 0.3048)
			(end 0.120396 0.2794)
			(stroke
				(width 0.1)
				(type default)
			)
			(layer "F.Fab")
		)
		(fp_line
			(start 0.12065 -0.3048)
			(end 0.67945 -0.3048)
			(stroke
				(width 0.1)
				(type default)
			)
			(layer "F.Fab")
		)
		(fp_line
			(start 0.12065 -0.2794)
			(end 0.12065 -0.3048)
			(stroke
				(width 0.1)
				(type default)
			)
			(layer "F.Fab")
		)
		(fp_line
			(start 0.67945 -0.3048)
			(end 0.67945 0.3048)
			(stroke
				(width 0.1)
				(type default)
			)
			(layer "F.Fab")
		)
		(fp_line
			(start 0.67945 0.3048)
			(end 0.120396 0.3048)
			(stroke
				(width 0.1)
				(type default)
			)
			(layer "F.Fab")
		)
		(pad "1" smd circle
			(at -0.40005 0)
			(size 0 0)
			(layers "F.Cu" "F.Mask" "F.Paste")
			(net "PVCCIN_CPU0_VCC")
		)
		(pad "2" smd circle
			(at 0.40005 0)
			(size 0 0)
			(layers "F.Cu" "F.Mask" "F.Paste")
			(net "GND")
		)
	)
	(footprint ""
		(layer "F.Cu")
		(at 169.422572 -418.479478 180)
		(property "Reference" "C1973"
			(at 0 0 180)
			(layer "F.SilkS")
			(hide yes)
			(effects
				(font
					(size 1.27 1.27)
				)
			)
		)
		(property "Value" ""
			(at 0 0 180)
			(layer "F.Fab")
			(effects
				(font
					(size 1.27 1.27)
				)
			)
		)
		(duplicate_pad_numbers_are_jumpers no)
		(fp_line
			(start 0.7874 0.4064)
			(end -0.7874 0.4064)
			(stroke
				(width 0.1524)
				(type default)
			)
			(layer "F.SilkS")
		)
		(fp_line
			(start 0.7874 -0.4064)
			(end 0.7874 0.4064)
			(stroke
				(width 0.1524)
				(type default)
			)
			(layer "F.SilkS")
		)
		(fp_line
			(start -0.7874 0.4064)
			(end -0.7874 -0.4064)
			(stroke
				(width 0.1524)
				(type default)
			)
			(layer "F.SilkS")
		)
		(fp_line
			(start -0.7874 -0.4064)
			(end 0.7874 -0.4064)
			(stroke
				(width 0.1524)
				(type default)
			)
			(layer "F.SilkS")
		)
		(fp_line
			(start 0.67945 0.3048)
			(end 0.120396 0.3048)
			(stroke
				(width 0.1)
				(type default)
			)
			(layer "F.Fab")
		)
		(fp_line
			(start 0.67945 -0.3048)
			(end 0.67945 0.3048)
			(stroke
				(width 0.1)
				(type default)
			)
			(layer "F.Fab")
		)
		(fp_line
			(start 0.12065 -0.2794)
			(end 0.12065 -0.3048)
			(stroke
				(width 0.1)
				(type default)
			)
			(layer "F.Fab")
		)
		(fp_line
			(start 0.12065 -0.3048)
			(end 0.67945 -0.3048)
			(stroke
				(width 0.1)
				(type default)
			)
			(layer "F.Fab")
		)
		(fp_line
			(start 0.120396 0.3048)
			(end 0.120396 0.2794)
			(stroke
				(width 0.1)
				(type default)
			)
			(layer "F.Fab")
		)
		(fp_line
			(start 0.120396 0.2794)
			(end -0.12065 0.2794)
			(stroke
				(width 0.1)
				(type default)
			)
			(layer "F.Fab")
		)
		(fp_line
			(start -0.12065 0.3048)
			(end -0.67945 0.3048)
			(stroke
				(width 0.1)
				(type default)
			)
			(layer "F.Fab")
		)
		(fp_line
			(start -0.12065 0.2794)
			(end -0.12065 0.3048)
			(stroke
				(width 0.1)
				(type default)
			)
			(layer "F.Fab")
		)
		(fp_line
			(start -0.12065 -0.2794)
			(end 0.12065 -0.2794)
			(stroke
				(width 0.1)
				(type default)
			)
			(layer "F.Fab")
		)
		(fp_line
			(start -0.12065 -0.305054)
			(end -0.12065 -0.2794)
			(stroke
				(width 0.1)
				(type default)
			)
			(layer "F.Fab")
		)
		(fp_line
			(start -0.67945 0.3048)
			(end -0.67945 -0.305054)
			(stroke
				(width 0.1)
				(type default)
			)
			(layer "F.Fab")
		)
		(fp_line
			(start -0.67945 -0.305054)
			(end -0.12065 -0.305054)
			(stroke
				(width 0.1)
				(type default)
			)
			(layer "F.Fab")
		)
		(pad "1" smd circle
			(at -0.40005 0 180)
			(size 0 0)
			(layers "F.Cu" "F.Mask" "F.Paste")
			(net "GPU_BASE_HMC_READY_ISO")
		)
		(pad "2" smd circle
			(at 0.40005 0 180)
			(size 0 0)
			(layers "F.Cu" "F.Mask" "F.Paste")
			(net "GND")
		)
	)
	(footprint ""
		(layer "F.Cu")
		(at 71.194676 -79.078836)
		(property "Reference" "D75"
			(at -37.31641 34.331402 90)
			(unlocked yes)
			(layer "F.SilkS")
			(effects
				(font
					(size 0.635 0.4064)
					(thickness 0.1524)
				)
				(justify left)
			)
		)
		(property "Value" ""
			(at 0 0 0)
			(layer "F.Fab")
			(effects
				(font
					(size 1.27 1.27)
				)
			)
		)
		(duplicate_pad_numbers_are_jumpers no)
		(fp_line
			(start -0.90678 0.4826)
			(end -0.90678 -0.4699)
			(stroke
				(width 0.1524)
				(type default)
			)
			(layer "F.SilkS")
		)
		(fp_line
			(start -0.89408 -0.4826)
			(end 0.90678 -0.4826)
			(stroke
				(width 0.1524)
				(type default)
			)
			(layer "F.SilkS")
		)
		(fp_line
			(start -0.79248 -0.4826)
			(end 1.03378 -0.4826)
			(stroke
				(width 0.1524)
				(type default)
			)
			(layer "F.SilkS")
		)
		(fp_line
			(start -0.64008 -0.4826)
			(end 1.16078 -0.4826)
			(stroke
				(width 0.1524)
				(type default)
			)
			(layer "F.SilkS")
		)
		(fp_line
			(start 0.90678 -0.4826)
			(end 0.90678 0.4826)
			(stroke
				(width 0.1524)
				(type default)
			)
			(layer "F.SilkS")
		)
		(fp_line
			(start 0.90678 0.4826)
			(end -0.90678 0.4826)
			(stroke
				(width 0.1524)
				(type default)
			)
			(layer "F.SilkS")
		)
		(fp_line
			(start 1.03378 -0.4826)
			(end 1.03378 0.4826)
			(stroke
				(width 0.1524)
				(type default)
			)
			(layer "F.SilkS")
		)
		(fp_line
			(start 1.03378 0.4826)
			(end -0.79248 0.4826)
			(stroke
				(width 0.1524)
				(type default)
			)
			(layer "F.SilkS")
		)
		(fp_line
			(start 1.16078 -0.4826)
			(end 1.16078 0.4826)
			(stroke
				(width 0.1524)
				(type default)
			)
			(layer "F.SilkS")
		)
		(fp_line
			(start 1.16078 0.4826)
			(end -0.64008 0.4826)
			(stroke
				(width 0.1524)
				(type default)
			)
			(layer "F.SilkS")
		)
		(fp_line
			(start -0.499872 -0.249936)
			(end 0.499872 -0.249936)
			(stroke
				(width 0.1)
				(type default)
			)
			(layer "F.Fab")
		)
		(fp_line
			(start -0.499872 0.249936)
			(end -0.499872 -0.249936)
			(stroke
				(width 0.1)
				(type default)
			)
			(layer "F.Fab")
		)
		(fp_line
			(start 0.499872 -0.249936)
			(end 0.499872 0.249936)
			(stroke
				(width 0.1)
				(type default)
			)
			(layer "F.Fab")
		)
		(fp_line
			(start 0.499872 0.249936)
			(end -0.499872 0.249936)
			(stroke
				(width 0.1)
				(type default)
			)
			(layer "F.Fab")
		)
		(pad "A" smd rect
			(at -0.47498 0)
			(size 0.6096 0.7112)
			(layers "F.Cu" "F.Mask" "F.Paste")
			(net "LED_PWRGD_PVCCFA_EHV_CPU0")
		)
		(pad "C" smd rect
			(at 0.47498 0)
			(size 0.6096 0.7112)
			(layers "F.Cu" "F.Mask" "F.Paste")
			(net "LED_PWRGD_PVCCFA_EHV_CPU0_D")
		)
	)
	(footprint ""
		(layer "F.Cu")
		(at 123.810522 -14.19733 180)
		(property "Reference" "R4184"
			(at 0 0 180)
			(layer "F.SilkS")
			(hide yes)
			(effects
				(font
					(size 1.27 1.27)
				)
			)
		)
		(property "Value" ""
			(at 0 0 180)
			(layer "F.Fab")
			(effects
				(font
					(size 1.27 1.27)
				)
			)
		)
		(duplicate_pad_numbers_are_jumpers no)
		(fp_line
			(start 0.7874 0.4064)
			(end -0.7874 0.4064)
			(stroke
				(width 0.1524)
				(type default)
			)
			(layer "F.SilkS")
		)
		(fp_line
			(start 0.7874 -0.4064)
			(end 0.7874 0.4064)
			(stroke
				(width 0.1524)
				(type default)
			)
			(layer "F.SilkS")
		)
		(fp_line
			(start -0.7874 0.4064)
			(end -0.7874 -0.4064)
			(stroke
				(width 0.1524)
				(type default)
			)
			(layer "F.SilkS")
		)
		(fp_line
			(start -0.7874 -0.4064)
			(end 0.7874 -0.4064)
			(stroke
				(width 0.1524)
				(type default)
			)
			(layer "F.SilkS")
		)
		(fp_line
			(start 0.67945 0.3048)
			(end 0.120396 0.3048)
			(stroke
				(width 0.1)
				(type default)
			)
			(layer "F.Fab")
		)
		(fp_line
			(start 0.67945 -0.3048)
			(end 0.67945 0.3048)
			(stroke
				(width 0.1)
				(type default)
			)
			(layer "F.Fab")
		)
		(fp_line
			(start 0.12065 -0.2794)
			(end 0.12065 -0.3048)
			(stroke
				(width 0.1)
				(type default)
			)
			(layer "F.Fab")
		)
		(fp_line
			(start 0.12065 -0.3048)
			(end 0.67945 -0.3048)
			(stroke
				(width 0.1)
				(type default)
			)
			(layer "F.Fab")
		)
		(fp_line
			(start 0.120396 0.3048)
			(end 0.120396 0.2794)
			(stroke
				(width 0.1)
				(type default)
			)
			(layer "F.Fab")
		)
		(fp_line
			(start 0.120396 0.2794)
			(end -0.12065 0.2794)
			(stroke
				(width 0.1)
				(type default)
			)
			(layer "F.Fab")
		)
		(fp_line
			(start -0.12065 0.3048)
			(end -0.67945 0.3048)
			(stroke
				(width 0.1)
				(type default)
			)
			(layer "F.Fab")
		)
		(fp_line
			(start -0.12065 0.2794)
			(end -0.12065 0.3048)
			(stroke
				(width 0.1)
				(type default)
			)
			(layer "F.Fab")
		)
		(fp_line
			(start -0.12065 -0.2794)
			(end 0.12065 -0.2794)
			(stroke
				(width 0.1)
				(type default)
			)
			(layer "F.Fab")
		)
		(fp_line
			(start -0.12065 -0.305054)
			(end -0.12065 -0.2794)
			(stroke
				(width 0.1)
				(type default)
			)
			(layer "F.Fab")
		)
		(fp_line
			(start -0.67945 0.3048)
			(end -0.67945 -0.305054)
			(stroke
				(width 0.1)
				(type default)
			)
			(layer "F.Fab")
		)
		(fp_line
			(start -0.67945 -0.305054)
			(end -0.12065 -0.305054)
			(stroke
				(width 0.1)
				(type default)
			)
			(layer "F.Fab")
		)
		(pad "1" smd circle
			(at -0.40005 0 180)
			(size 0 0)
			(layers "F.Cu" "F.Mask" "F.Paste")
			(net "P3V3_AUX")
		)
		(pad "2" smd circle
			(at 0.40005 0 180)
			(size 0 0)
			(layers "F.Cu" "F.Mask" "F.Paste")
			(net "U273_3_ADD2")
		)
	)
	(footprint ""
		(layer "F.Cu")
		(at 163.12515 -432.865276 -90)
		(property "Reference" "R3105"
			(at 0 0 270)
			(layer "F.SilkS")
			(hide yes)
			(effects
				(font
					(size 1.27 1.27)
				)
			)
		)
		(property "Value" ""
			(at 0 0 270)
			(layer "F.Fab")
			(effects
				(font
					(size 1.27 1.27)
				)
			)
		)
		(duplicate_pad_numbers_are_jumpers no)
		(fp_line
			(start -0.7874 0.4064)
			(end -0.7874 -0.4064)
			(stroke
				(width 0.1524)
				(type default)
			)
			(layer "F.SilkS")
		)
		(fp_line
			(start 0.7874 0.4064)
			(end -0.7874 0.4064)
			(stroke
				(width 0.1524)
				(type default)
			)
			(layer "F.SilkS")
		)
		(fp_line
			(start -0.7874 -0.4064)
			(end 0.7874 -0.4064)
			(stroke
				(width 0.1524)
				(type default)
			)
			(layer "F.SilkS")
		)
		(fp_line
			(start 0.7874 -0.4064)
			(end 0.7874 0.4064)
			(stroke
				(width 0.1524)
				(type default)
			)
			(layer "F.SilkS")
		)
		(fp_line
			(start -0.67945 0.3048)
			(end -0.67945 -0.305054)
			(stroke
				(width 0.1)
				(type default)
			)
			(layer "F.Fab")
		)
		(fp_line
			(start -0.12065 0.3048)
			(end -0.67945 0.3048)
			(stroke
				(width 0.1)
				(type default)
			)
			(layer "F.Fab")
		)
		(fp_line
			(start 0.120396 0.3048)
			(end 0.120396 0.2794)
			(stroke
				(width 0.1)
				(type default)
			)
			(layer "F.Fab")
		)
		(fp_line
			(start 0.67945 0.3048)
			(end 0.120396 0.3048)
			(stroke
				(width 0.1)
				(type default)
			)
			(layer "F.Fab")
		)
		(fp_line
			(start -0.12065 0.2794)
			(end -0.12065 0.3048)
			(stroke
				(width 0.1)
				(type default)
			)
			(layer "F.Fab")
		)
		(fp_line
			(start 0.120396 0.2794)
			(end -0.12065 0.2794)
			(stroke
				(width 0.1)
				(type default)
			)
			(layer "F.Fab")
		)
		(fp_line
			(start -0.12065 -0.2794)
			(end 0.12065 -0.2794)
			(stroke
				(width 0.1)
				(type default)
			)
			(layer "F.Fab")
		)
		(fp_line
			(start 0.12065 -0.2794)
			(end 0.12065 -0.3048)
			(stroke
				(width 0.1)
				(type default)
			)
			(layer "F.Fab")
		)
		(fp_line
			(start 0.12065 -0.3048)
			(end 0.67945 -0.3048)
			(stroke
				(width 0.1)
				(type default)
			)
			(layer "F.Fab")
		)
		(fp_line
			(start 0.67945 -0.3048)
			(end 0.67945 0.3048)
			(stroke
				(width 0.1)
				(type default)
			)
			(layer "F.Fab")
		)
		(fp_line
			(start -0.67945 -0.305054)
			(end -0.12065 -0.305054)
			(stroke
				(width 0.1)
				(type default)
			)
			(layer "F.Fab")
		)
		(fp_line
			(start -0.12065 -0.305054)
			(end -0.12065 -0.2794)
			(stroke
				(width 0.1)
				(type default)
			)
			(layer "F.Fab")
		)
		(pad "1" smd circle
			(at -0.40005 0 270)
			(size 0 0)
			(layers "F.Cu" "F.Mask" "F.Paste")
			(net "SMB_BMC_SWB_SCL")
		)
		(pad "2" smd circle
			(at 0.40005 0 270)
			(size 0 0)
			(layers "F.Cu" "F.Mask" "F.Paste")
			(net "SMB_BMC_SWB_R_SCL")
		)
	)
)
